# T6G (Grand Teton) — schematic netlist excerpt (pin names and nets, part order shuffled) for the footprints in the layout excerpt that follows; sources: Cadence DE-HDL packaged netlist, KiCad conversion of 04192023_DAF0TMB3IC0_F0TG_MB_C_brd_V02_OCP.brd

PR2530  Q_RES  10 1% CHIP  pkg 0402LF  page 266 : A = P12V_HSC_GATE_G3 ; B = P12V_HSC_GATE2
R3933  Q_RES  16.9K 1% CHIP  pkg 0402LF  page 262 : A = P12V_AUX ; B = MB0_P12V_STBY_PWRGD
PC570  Q_CAP  22UF 16V 20% X6S  pkg C0805  page 190 : A = SW_P3V3_AUX_FLT ; B = GND

(kicad_pcb
	(version 20260206)
	(generator "pcbnew")
	(generator_version "10.0")
	(general
		(thickness 1.6)
		(legacy_teardrops no)
	)
	(paper "A4")
	(title_block
		(title "04192023_DAF0TMB3IC0_F0TG_MB_C_brd_V02_OCP.brd")
		(comment 1 "Grand Teton / footprints 1324-1326 of 8354")
	)
	(layers
		(0 "F.Cu" signal "TOP")
		(4 "In1.Cu" signal "GND")
		(6 "In2.Cu" signal "IN1")
		(8 "In3.Cu" signal "GND1")
		(10 "In4.Cu" signal "IN2")
		(12 "In5.Cu" signal "GND2")
		(14 "In6.Cu" signal "IN3")
		(16 "In7.Cu" signal "GND3")
		(18 "In8.Cu" signal "VCC")
		(20 "In9.Cu" signal "VCC1")
		(22 "In10.Cu" signal "GND4")
		(24 "In11.Cu" signal "IN4")
		(26 "In12.Cu" signal "GND5")
		(28 "In13.Cu" signal "IN5")
		(30 "In14.Cu" signal "GND6")
		(32 "In15.Cu" signal "IN6")
		(34 "In16.Cu" signal "GND7")
		(2 "B.Cu" signal "BOTTOM")
		(9 "F.Adhes" user "F.Adhesive")
		(11 "B.Adhes" user "B.Adhesive")
		(13 "F.Paste" user "Package Geometry/Pastemask Top")
		(15 "B.Paste" user "Package Geometry/Pastemask Bottom")
		(5 "F.SilkS" user "Ref Des/Silkscreen Top")
		(7 "B.SilkS" user "Ref Des/Silkscreen Bottom")
		(1 "F.Mask" user "Board Geometry/Soldermask Top")
		(3 "B.Mask" user "Board Geometry/Soldermask Bottom")
		(17 "Dwgs.User" user "User.Drawings")
		(19 "Cmts.User" user "User.Comments")
		(21 "Eco1.User" user "User.Eco1")
		(23 "Eco2.User" user "User.Eco2")
		(25 "Edge.Cuts" user "Board Geometry/Outline")
		(27 "Margin" user)
		(31 "F.CrtYd" user "Package Geometry/Place Bound Top")
		(29 "B.CrtYd" user "Package Geometry/Place Bound Bottom")
		(35 "F.Fab" user "Ref Des/Assembly Top")
		(33 "B.Fab" user "Ref Des/Assembly Bottom")
	)
	(footprint ""
		(layer "F.Cu")
		(at 178.689 -408.559)
		(property "Reference" "R3933"
			(at 0 0 0)
			(layer "F.SilkS")
			(hide yes)
			(effects
				(font
					(size 1.27 1.27)
				)
			)
		)
		(property "Value" ""
			(at 0 0 0)
			(layer "F.Fab")
			(effects
				(font
					(size 1.27 1.27)
				)
			)
		)
		(duplicate_pad_numbers_are_jumpers no)
		(fp_line
			(start -0.7874 -0.4064)
			(end 0.7874 -0.4064)
			(stroke
				(width 0.1524)
				(type default)
			)
			(layer "F.SilkS")
		)
		(fp_line
			(start -0.7874 0.4064)
			(end -0.7874 -0.4064)
			(stroke
				(width 0.1524)
				(type default)
			)
			(layer "F.SilkS")
		)
		(fp_line
			(start 0.7874 -0.4064)
			(end 0.7874 0.4064)
			(stroke
				(width 0.1524)
				(type default)
			)
			(layer "F.SilkS")
		)
		(fp_line
			(start 0.7874 0.4064)
			(end -0.7874 0.4064)
			(stroke
				(width 0.1524)
				(type default)
			)
			(layer "F.SilkS")
		)
		(fp_line
			(start -0.67945 -0.305054)
			(end -0.12065 -0.305054)
			(stroke
				(width 0.1)
				(type default)
			)
			(layer "F.Fab")
		)
		(fp_line
			(start -0.67945 0.3048)
			(end -0.67945 -0.305054)
			(stroke
				(width 0.1)
				(type default)
			)
			(layer "F.Fab")
		)
		(fp_line
			(start -0.12065 -0.305054)
			(end -0.12065 -0.2794)
			(stroke
				(width 0.1)
				(type default)
			)
			(layer "F.Fab")
		)
		(fp_line
			(start -0.12065 -0.2794)
			(end 0.12065 -0.2794)
			(stroke
				(width 0.1)
				(type default)
			)
			(layer "F.Fab")
		)
		(fp_line
			(start -0.12065 0.2794)
			(end -0.12065 0.3048)
			(stroke
				(width 0.1)
				(type default)
			)
			(layer "F.Fab")
		)
		(fp_line
			(start -0.12065 0.3048)
			(end -0.67945 0.3048)
			(stroke
				(width 0.1)
				(type default)
			)
			(layer "F.Fab")
		)
		(fp_line
			(start 0.120396 0.2794)
			(end -0.12065 0.2794)
			(stroke
				(width 0.1)
				(type default)
			)
			(layer "F.Fab")
		)
		(fp_line
			(start 0.120396 0.3048)
			(end 0.120396 0.2794)
			(stroke
				(width 0.1)
				(type default)
			)
			(layer "F.Fab")
		)
		(fp_line
			(start 0.12065 -0.3048)
			(end 0.67945 -0.3048)
			(stroke
				(width 0.1)
				(type default)
			)
			(layer "F.Fab")
		)
		(fp_line
			(start 0.12065 -0.2794)
			(end 0.12065 -0.3048)
			(stroke
				(width 0.1)
				(type default)
			)
			(layer "F.Fab")
		)
		(fp_line
			(start 0.67945 -0.3048)
			(end 0.67945 0.3048)
			(stroke
				(width 0.1)
				(type default)
			)
			(layer "F.Fab")
		)
		(fp_line
			(start 0.67945 0.3048)
			(end 0.120396 0.3048)
			(stroke
				(width 0.1)
				(type default)
			)
			(layer "F.Fab")
		)
		(pad "1" smd circle
			(at -0.40005 0)
			(size 0 0)
			(layers "F.Cu" "F.Mask" "F.Paste")
			(net "P12V_AUX")
		)
		(pad "2" smd circle
			(at 0.40005 0)
			(size 0 0)
			(layers "F.Cu" "F.Mask" "F.Paste")
			(net "MB0_P12V_STBY_PWRGD")
		)
	)
	(footprint ""
		(layer "F.Cu")
		(at 451.573392 -52.84851 90)
		(property "Reference" "PC570"
			(at 0 0 90)
			(layer "F.SilkS")
			(hide yes)
			(effects
				(font
					(size 1.27 1.27)
				)
			)
		)
		(property "Value" ""
			(at 0 0 90)
			(layer "F.Fab")
			(effects
				(font
					(size 1.27 1.27)
				)
			)
		)
		(duplicate_pad_numbers_are_jumpers no)
		(fp_line
			(start 1.524 -0.762)
			(end 1.524 0.762)
			(stroke
				(width 0.1524)
				(type default)
			)
			(layer "F.SilkS")
		)
		(fp_line
			(start -1.524 -0.762)
			(end 1.524 -0.762)
			(stroke
				(width 0.1524)
				(type default)
			)
			(layer "F.SilkS")
		)
		(fp_line
			(start 1.524 0.762)
			(end -1.524 0.762)
			(stroke
				(width 0.1524)
				(type default)
			)
			(layer "F.SilkS")
		)
		(fp_line
			(start -1.524 0.762)
			(end -1.524 -0.762)
			(stroke
				(width 0.1524)
				(type default)
			)
			(layer "F.SilkS")
		)
		(fp_line
			(start 1.1049 -0.724916)
			(end -1.1049 -0.724916)
			(stroke
				(width 0.1)
				(type default)
			)
			(layer "F.Fab")
		)
		(fp_line
			(start -1.1049 -0.724916)
			(end -1.1049 0.724916)
			(stroke
				(width 0.1)
				(type default)
			)
			(layer "F.Fab")
		)
		(fp_line
			(start 1.1049 0.724916)
			(end 1.1049 -0.724916)
			(stroke
				(width 0.1)
				(type default)
			)
			(layer "F.Fab")
		)
		(fp_line
			(start -1.1049 0.724916)
			(end 1.1049 0.724916)
			(stroke
				(width 0.1)
				(type default)
			)
			(layer "F.Fab")
		)
		(pad "1" smd rect
			(at -0.889 0 270)
			(size 1.016 1.27)
			(layers "F.Cu" "F.Mask" "F.Paste")
			(net "SW_P3V3_AUX_FLT")
		)
		(pad "2" smd rect
			(at 0.889 0 270)
			(size 1.016 1.27)
			(layers "F.Cu" "F.Mask" "F.Paste")
			(net "GND")
		)
	)
	(footprint ""
		(layer "F.Cu")
		(at 267.701014 -380.66853)
		(property "Reference" "PR2530"
			(at 0 0 0)
			(layer "F.SilkS")
			(hide yes)
			(effects
				(font
					(size 1.27 1.27)
				)
			)
		)
		(property "Value" ""
			(at 0 0 0)
			(layer "F.Fab")
			(effects
				(font
					(size 1.27 1.27)
				)
			)
		)
		(duplicate_pad_numbers_are_jumpers no)
		(fp_line
			(start -0.7874 -0.4064)
			(end 0.7874 -0.4064)
			(stroke
				(width 0.1524)
				(type default)
			)
			(layer "F.SilkS")
		)
		(fp_line
			(start -0.7874 0.4064)
			(end -0.7874 -0.4064)
			(stroke
				(width 0.1524)
				(type default)
			)
			(layer "F.SilkS")
		)
		(fp_line
			(start 0.7874 -0.4064)
			(end 0.7874 0.4064)
			(stroke
				(width 0.1524)
				(type default)
			)
			(layer "F.SilkS")
		)
		(fp_line
			(start 0.7874 0.4064)
			(end -0.7874 0.4064)
			(stroke
				(width 0.1524)
				(type default)
			)
			(layer "F.SilkS")
		)
		(fp_line
			(start -0.67945 -0.305054)
			(end -0.12065 -0.305054)
			(stroke
				(width 0.1)
				(type default)
			)
			(layer "F.Fab")
		)
		(fp_line
			(start -0.67945 0.3048)
			(end -0.67945 -0.305054)
			(stroke
				(width 0.1)
				(type default)
			)
			(layer "F.Fab")
		)
		(fp_line
			(start -0.12065 -0.305054)
			(end -0.12065 -0.2794)
			(stroke
				(width 0.1)
				(type default)
			)
			(layer "F.Fab")
		)
		(fp_line
			(start -0.12065 -0.2794)
			(end 0.12065 -0.2794)
			(stroke
				(width 0.1)
				(type default)
			)
			(layer "F.Fab")
		)
		(fp_line
			(start -0.12065 0.2794)
			(end -0.12065 0.3048)
			(stroke
				(width 0.1)
				(type default)
			)
			(layer "F.Fab")
		)
		(fp_line
			(start -0.12065 0.3048)
			(end -0.67945 0.3048)
			(stroke
				(width 0.1)
				(type default)
			)
			(layer "F.Fab")
		)
		(fp_line
			(start 0.120396 0.2794)
			(end -0.12065 0.2794)
			(stroke
				(width 0.1)
				(type default)
			)
			(layer "F.Fab")
		)
		(fp_line
			(start 0.120396 0.3048)
			(end 0.120396 0.2794)
			(stroke
				(width 0.1)
				(type default)
			)
			(layer "F.Fab")
		)
		(fp_line
			(start 0.12065 -0.3048)
			(end 0.67945 -0.3048)
			(stroke
				(width 0.1)
				(type default)
			)
			(layer "F.Fab")
		)
		(fp_line
			(start 0.12065 -0.2794)
			(end 0.12065 -0.3048)
			(stroke
				(width 0.1)
				(type default)
			)
			(layer "F.Fab")
		)
		(fp_line
			(start 0.67945 -0.3048)
			(end 0.67945 0.3048)
			(stroke
				(width 0.1)
				(type default)
			)
			(layer "F.Fab")
		)
		(fp_line
			(start 0.67945 0.3048)
			(end 0.120396 0.3048)
			(stroke
				(width 0.1)
				(type default)
			)
			(layer "F.Fab")
		)
		(pad "1" smd circle
			(at -0.40005 0)
			(size 0 0)
			(layers "F.Cu" "F.Mask" "F.Paste")
			(net "P12V_HSC_GATE_G3")
		)
		(pad "2" smd circle
			(at 0.40005 0)
			(size 0 0)
			(layers "F.Cu" "F.Mask" "F.Paste")
			(net "P12V_HSC_GATE2")
		)
	)
)
